(kicad_pcb
	(version 20260206)
	(generator "pcbnew")
	(generator_version "10.0")
	(general
		(thickness 1.6)
		(legacy_teardrops no)
	)
	(paper "A4")
	(title_block
		(title "12092022_DA0F0TMDCD0_F0T_Management_Board_D_brd_V3_OCP.brd")
		(comment 1 "Grand Teton / footprints 509-514 of 1440")
	)
	(layers
		(0 "F.Cu" signal "TOP")
		(4 "In1.Cu" signal "GND")
		(6 "In2.Cu" signal "IN1")
		(8 "In3.Cu" signal "GND1")
		(10 "In4.Cu" signal "IN2")
		(12 "In5.Cu" signal "VCC")
		(14 "In6.Cu" signal "VCC1")
		(16 "In7.Cu" signal "IN3")
		(18 "In8.Cu" signal "GND2")
		(20 "In9.Cu" signal "IN4")
		(22 "In10.Cu" signal "GND3")
		(2 "B.Cu" signal "BOTTOM")
		(9 "F.Adhes" user "F.Adhesive")
		(11 "B.Adhes" user "B.Adhesive")
		(13 "F.Paste" user "Package Geometry/Pastemask Top")
		(15 "B.Paste" user "Package Geometry/Pastemask Bottom")
		(5 "F.SilkS" user "Ref Des/Silkscreen Top")
		(7 "B.SilkS" user "Ref Des/Silkscreen Bottom")
		(1 "F.Mask" user "Board Geometry/Soldermask Top")
		(3 "B.Mask" user "Board Geometry/Soldermask Bottom")
		(17 "Dwgs.User" user "User.Drawings")
		(19 "Cmts.User" user "User.Comments")
		(21 "Eco1.User" user "User.Eco1")
		(23 "Eco2.User" user "User.Eco2")
		(25 "Edge.Cuts" user "Board Geometry/Outline")
		(27 "Margin" user)
		(31 "F.CrtYd" user "Package Geometry/Place Bound Top")
		(29 "B.CrtYd" user "Package Geometry/Place Bound Bottom")
		(35 "F.Fab" user "Ref Des/Assembly Top")
		(33 "B.Fab" user "Ref Des/Assembly Bottom")
	)
	(footprint ""
		(layer "F.Cu")
		(at 112.014 62.23 90)
		(property "Reference" "X17"
			(at -2.07137 1.0795 0)
			(unlocked yes)
			(layer "F.SilkS")
			(effects
				(font
					(size 0.7874 0.5842)
					(thickness 0.1524)
				)
				(justify left)
			)
		)
		(property "Value" ""
			(at 0 0 90)
			(layer "F.Fab")
			(effects
				(font
					(size 1.27 1.27)
				)
			)
		)
		(property "Device Type" "TP_TDR_4P_FTS_TH-TP_TDR_4P_DIPA"
			(at 1.30175 1.27 180)
			(unlocked yes)
			(layer "F.Fab")
			(hide yes)
			(effects
				(font
					(size 0.635 0.4064)
					(thickness 0.1524)
				)
			)
		)
		(property "User Part Number" "N_A"
			(at 1.30175 1.27 180)
			(unlocked yes)
			(layer "Cmts.User")
			(hide yes)
			(effects
				(font
					(size 0.635 0.4064)
					(thickness 0.1524)
				)
			)
		)
		(duplicate_pad_numbers_are_jumpers no)
		(fp_line
			(start 2.54 -1.27)
			(end 0 -1.27)
			(stroke
				(width 0.1524)
				(type default)
			)
			(layer "F.SilkS")
		)
		(fp_line
			(start 0 -1.27)
			(end 0 -0.635)
			(stroke
				(width 0.1524)
				(type default)
			)
			(layer "F.SilkS")
		)
		(fp_line
			(start 2.54 -1.1303)
			(end 2.54 -1.27)
			(stroke
				(width 0.1524)
				(type default)
			)
			(layer "F.SilkS")
		)
		(fp_line
			(start 0 0.635)
			(end 0 1.905)
			(stroke
				(width 0.1524)
				(type default)
			)
			(layer "F.SilkS")
		)
		(fp_line
			(start 2.54 1.4097)
			(end 2.54 1.1303)
			(stroke
				(width 0.1524)
				(type default)
			)
			(layer "F.SilkS")
		)
		(fp_line
			(start 0 3.175)
			(end 0 3.81)
			(stroke
				(width 0.1524)
				(type default)
			)
			(layer "F.SilkS")
		)
		(fp_line
			(start 2.54 3.81)
			(end 2.54 3.6703)
			(stroke
				(width 0.1524)
				(type default)
			)
			(layer "F.SilkS")
		)
		(fp_line
			(start 0 3.81)
			(end 2.54 3.81)
			(stroke
				(width 0.1524)
				(type default)
			)
			(layer "F.SilkS")
		)
		(fp_poly
			(pts
				(xy -0.761746 0) (xy -2.285746 -0.762) (xy -2.285746 0.762)
			)
			(stroke
				(width 0)
				(type default)
			)
			(fill yes)
			(layer "F.SilkS")
		)
		(fp_line
			(start 2.54 -1.27)
			(end 0 -1.27)
			(stroke
				(width 0.1)
				(type default)
			)
			(layer "F.Fab")
		)
		(fp_line
			(start 0 -1.27)
			(end 0 3.81)
			(stroke
				(width 0.1)
				(type default)
			)
			(layer "F.Fab")
		)
		(fp_line
			(start 2.54 3.81)
			(end 2.54 -1.27)
			(stroke
				(width 0.1)
				(type default)
			)
			(layer "F.Fab")
		)
		(fp_line
			(start 0 3.81)
			(end 2.54 3.81)
			(stroke
				(width 0.1)
				(type default)
			)
			(layer "F.Fab")
		)
		(fp_poly
			(pts
				(xy -0.761746 0) (xy -2.285746 -0.762) (xy -2.285746 0.762)
			)
			(stroke
				(width 0)
				(type default)
			)
			(fill yes)
			(layer "F.Fab")
		)
		(pad "1" thru_hole circle
			(at 0 0 90)
			(size 1.0033 1.0033)
			(drill 0.249936)
			(layers "*.Cu" "*.Mask")
			(remove_unused_layers no)
			(net "TDR_DIFF_100_IN4_DP")
			(clearance 0.10795)
			(thermal_gap 0.10795)
			(padstack
				(mode front_inner_back)
				(layer "Inner"
					(shape circle)
					(size 0.8001 0.8001)
					(clearance 0.1524)
				)
				(layer "B.Cu"
					(shape circle)
					(size 1.0033 1.0033)
					(clearance 0.10795)
				)
			)
		)
		(pad "2" thru_hole circle
			(at 2.54 0 90)
			(size 1.9939 1.9939)
			(drill 0.249936)
			(layers "*.Cu" "*.Mask")
			(remove_unused_layers no)
			(net "GND_P1")
			(clearance 0.10795)
			(thermal_gap 0.10795)
			(padstack
				(mode front_inner_back)
				(layer "Inner"
					(shape circle)
					(size 0.8001 0.8001)
					(clearance 0.1524)
				)
				(layer "B.Cu"
					(shape circle)
					(size 1.9939 1.9939)
					(clearance 0.10795)
				)
			)
		)
		(pad "3" thru_hole circle
			(at 2.54 2.54 90)
			(size 1.9939 1.9939)
			(drill 0.249936)
			(layers "*.Cu" "*.Mask")
			(remove_unused_layers no)
			(net "GND_P1")
			(clearance 0.10795)
			(thermal_gap 0.10795)
			(padstack
				(mode front_inner_back)
				(layer "Inner"
					(shape circle)
					(size 0.8001 0.8001)
					(clearance 0.1524)
				)
				(layer "B.Cu"
					(shape circle)
					(size 1.9939 1.9939)
					(clearance 0.10795)
				)
			)
		)
		(pad "4" thru_hole circle
			(at 0 2.54 90)
			(size 1.0033 1.0033)
			(drill 0.249936)
			(layers "*.Cu" "*.Mask")
			(remove_unused_layers no)
			(net "TDR_DIFF_100_IN4_DN")
			(clearance 0.10795)
			(thermal_gap 0.10795)
			(padstack
				(mode front_inner_back)
				(layer "Inner"
					(shape circle)
					(size 0.8001 0.8001)
					(clearance 0.1524)
				)
				(layer "B.Cu"
					(shape circle)
					(size 1.0033 1.0033)
					(clearance 0.10795)
				)
			)
		)
	)
	(footprint ""
		(layer "F.Cu")
		(at 60.36437 -34.637726 90)
		(property "Reference" "R203"
			(at 0 0 90)
			(layer "F.SilkS")
			(hide yes)
			(effects
				(font
					(size 1.27 1.27)
				)
			)
		)
		(property "Value" ""
			(at 0 0 90)
			(layer "F.Fab")
			(effects
				(font
					(size 1.27 1.27)
				)
			)
		)
		(duplicate_pad_numbers_are_jumpers no)
		(fp_line
			(start 0.7874 -0.4064)
			(end 0.7874 0.4064)
			(stroke
				(width 0.1524)
				(type default)
			)
			(layer "F.SilkS")
		)
		(fp_line
			(start -0.7874 -0.4064)
			(end 0.7874 -0.4064)
			(stroke
				(width 0.1524)
				(type default)
			)
			(layer "F.SilkS")
		)
		(fp_line
			(start 0.7874 0.4064)
			(end -0.7874 0.4064)
			(stroke
				(width 0.1524)
				(type default)
			)
			(layer "F.SilkS")
		)
		(fp_line
			(start -0.7874 0.4064)
			(end -0.7874 -0.4064)
			(stroke
				(width 0.1524)
				(type default)
			)
			(layer "F.SilkS")
		)
		(fp_line
			(start -0.12065 -0.305054)
			(end -0.12065 -0.2794)
			(stroke
				(width 0.1)
				(type default)
			)
			(layer "F.Fab")
		)
		(fp_line
			(start -0.67945 -0.305054)
			(end -0.12065 -0.305054)
			(stroke
				(width 0.1)
				(type default)
			)
			(layer "F.Fab")
		)
		(fp_line
			(start 0.67945 -0.3048)
			(end 0.67945 0.3048)
			(stroke
				(width 0.1)
				(type default)
			)
			(layer "F.Fab")
		)
		(fp_line
			(start 0.12065 -0.3048)
			(end 0.67945 -0.3048)
			(stroke
				(width 0.1)
				(type default)
			)
			(layer "F.Fab")
		)
		(fp_line
			(start 0.12065 -0.2794)
			(end 0.12065 -0.3048)
			(stroke
				(width 0.1)
				(type default)
			)
			(layer "F.Fab")
		)
		(fp_line
			(start -0.12065 -0.2794)
			(end 0.12065 -0.2794)
			(stroke
				(width 0.1)
				(type default)
			)
			(layer "F.Fab")
		)
		(fp_line
			(start 0.120396 0.2794)
			(end -0.12065 0.2794)
			(stroke
				(width 0.1)
				(type default)
			)
			(layer "F.Fab")
		)
		(fp_line
			(start -0.12065 0.2794)
			(end -0.12065 0.3048)
			(stroke
				(width 0.1)
				(type default)
			)
			(layer "F.Fab")
		)
		(fp_line
			(start 0.67945 0.3048)
			(end 0.120396 0.3048)
			(stroke
				(width 0.1)
				(type default)
			)
			(layer "F.Fab")
		)
		(fp_line
			(start 0.120396 0.3048)
			(end 0.120396 0.2794)
			(stroke
				(width 0.1)
				(type default)
			)
			(layer "F.Fab")
		)
		(fp_line
			(start -0.12065 0.3048)
			(end -0.67945 0.3048)
			(stroke
				(width 0.1)
				(type default)
			)
			(layer "F.Fab")
		)
		(fp_line
			(start -0.67945 0.3048)
			(end -0.67945 -0.305054)
			(stroke
				(width 0.1)
				(type default)
			)
			(layer "F.Fab")
		)
		(pad "1" smd circle
			(at -0.40005 0 90)
			(size 0 0)
			(layers "F.Cu" "F.Mask" "F.Paste")
			(net "P3V3_RGM")
		)
		(pad "2" smd circle
			(at 0.40005 0 90)
			(size 0 0)
			(layers "F.Cu" "F.Mask" "F.Paste")
			(net "JTAG_SCM_TMS")
		)
	)
	(footprint ""
		(layer "F.Cu")
		(at 45.72 -34.6202 90)
		(property "Reference" "R705"
			(at 0 0 90)
			(layer "F.SilkS")
			(hide yes)
			(effects
				(font
					(size 1.27 1.27)
				)
			)
		)
		(property "Value" ""
			(at 0 0 90)
			(layer "F.Fab")
			(effects
				(font
					(size 1.27 1.27)
				)
			)
		)
		(duplicate_pad_numbers_are_jumpers no)
		(fp_line
			(start 0.7874 -0.4064)
			(end 0.7874 0.4064)
			(stroke
				(width 0.1524)
				(type default)
			)
			(layer "F.SilkS")
		)
		(fp_line
			(start -0.7874 -0.4064)
			(end 0.7874 -0.4064)
			(stroke
				(width 0.1524)
				(type default)
			)
			(layer "F.SilkS")
		)
		(fp_line
			(start 0.7874 0.4064)
			(end -0.7874 0.4064)
			(stroke
				(width 0.1524)
				(type default)
			)
			(layer "F.SilkS")
		)
		(fp_line
			(start -0.7874 0.4064)
			(end -0.7874 -0.4064)
			(stroke
				(width 0.1524)
				(type default)
			)
			(layer "F.SilkS")
		)
		(fp_line
			(start -0.12065 -0.305054)
			(end -0.12065 -0.2794)
			(stroke
				(width 0.1)
				(type default)
			)
			(layer "F.Fab")
		)
		(fp_line
			(start -0.67945 -0.305054)
			(end -0.12065 -0.305054)
			(stroke
				(width 0.1)
				(type default)
			)
			(layer "F.Fab")
		)
		(fp_line
			(start 0.67945 -0.3048)
			(end 0.67945 0.3048)
			(stroke
				(width 0.1)
				(type default)
			)
			(layer "F.Fab")
		)
		(fp_line
			(start 0.12065 -0.3048)
			(end 0.67945 -0.3048)
			(stroke
				(width 0.1)
				(type default)
			)
			(layer "F.Fab")
		)
		(fp_line
			(start 0.12065 -0.2794)
			(end 0.12065 -0.3048)
			(stroke
				(width 0.1)
				(type default)
			)
			(layer "F.Fab")
		)
		(fp_line
			(start -0.12065 -0.2794)
			(end 0.12065 -0.2794)
			(stroke
				(width 0.1)
				(type default)
			)
			(layer "F.Fab")
		)
		(fp_line
			(start 0.120396 0.2794)
			(end -0.12065 0.2794)
			(stroke
				(width 0.1)
				(type default)
			)
			(layer "F.Fab")
		)
		(fp_line
			(start -0.12065 0.2794)
			(end -0.12065 0.3048)
			(stroke
				(width 0.1)
				(type default)
			)
			(layer "F.Fab")
		)
		(fp_line
			(start 0.67945 0.3048)
			(end 0.120396 0.3048)
			(stroke
				(width 0.1)
				(type default)
			)
			(layer "F.Fab")
		)
		(fp_line
			(start 0.120396 0.3048)
			(end 0.120396 0.2794)
			(stroke
				(width 0.1)
				(type default)
			)
			(layer "F.Fab")
		)
		(fp_line
			(start -0.12065 0.3048)
			(end -0.67945 0.3048)
			(stroke
				(width 0.1)
				(type default)
			)
			(layer "F.Fab")
		)
		(fp_line
			(start -0.67945 0.3048)
			(end -0.67945 -0.305054)
			(stroke
				(width 0.1)
				(type default)
			)
			(layer "F.Fab")
		)
		(pad "1" smd circle
			(at -0.40005 0 90)
			(size 0 0)
			(layers "F.Cu" "F.Mask" "F.Paste")
			(net "FM_BMC_DBP_PRESENT_N")
		)
		(pad "2" smd circle
			(at 0.40005 0 90)
			(size 0 0)
			(layers "F.Cu" "F.Mask" "F.Paste")
			(net "FM_BMC_DBP_PRESENT_R_N")
		)
	)
	(footprint ""
		(layer "F.Cu")
		(at 54.040278 -34.637726 -90)
		(property "Reference" "R20"
			(at 0 0 270)
			(layer "F.SilkS")
			(hide yes)
			(effects
				(font
					(size 1.27 1.27)
				)
			)
		)
		(property "Value" ""
			(at 0 0 270)
			(layer "F.Fab")
			(effects
				(font
					(size 1.27 1.27)
				)
			)
		)
		(duplicate_pad_numbers_are_jumpers no)
		(fp_line
			(start -0.7874 0.4064)
			(end -0.7874 -0.4064)
			(stroke
				(width 0.1524)
				(type default)
			)
			(layer "F.SilkS")
		)
		(fp_line
			(start 0.7874 0.4064)
			(end -0.7874 0.4064)
			(stroke
				(width 0.1524)
				(type default)
			)
			(layer "F.SilkS")
		)
		(fp_line
			(start -0.7874 -0.4064)
			(end 0.7874 -0.4064)
			(stroke
				(width 0.1524)
				(type default)
			)
			(layer "F.SilkS")
		)
		(fp_line
			(start 0.7874 -0.4064)
			(end 0.7874 0.4064)
			(stroke
				(width 0.1524)
				(type default)
			)
			(layer "F.SilkS")
		)
		(fp_line
			(start -0.67945 0.3048)
			(end -0.67945 -0.305054)
			(stroke
				(width 0.1)
				(type default)
			)
			(layer "F.Fab")
		)
		(fp_line
			(start -0.12065 0.3048)
			(end -0.67945 0.3048)
			(stroke
				(width 0.1)
				(type default)
			)
			(layer "F.Fab")
		)
		(fp_line
			(start 0.120396 0.3048)
			(end 0.120396 0.2794)
			(stroke
				(width 0.1)
				(type default)
			)
			(layer "F.Fab")
		)
		(fp_line
			(start 0.67945 0.3048)
			(end 0.120396 0.3048)
			(stroke
				(width 0.1)
				(type default)
			)
			(layer "F.Fab")
		)
		(fp_line
			(start -0.12065 0.2794)
			(end -0.12065 0.3048)
			(stroke
				(width 0.1)
				(type default)
			)
			(layer "F.Fab")
		)
		(fp_line
			(start 0.120396 0.2794)
			(end -0.12065 0.2794)
			(stroke
				(width 0.1)
				(type default)
			)
			(layer "F.Fab")
		)
		(fp_line
			(start -0.12065 -0.2794)
			(end 0.12065 -0.2794)
			(stroke
				(width 0.1)
				(type default)
			)
			(layer "F.Fab")
		)
		(fp_line
			(start 0.12065 -0.2794)
			(end 0.12065 -0.3048)
			(stroke
				(width 0.1)
				(type default)
			)
			(layer "F.Fab")
		)
		(fp_line
			(start 0.12065 -0.3048)
			(end 0.67945 -0.3048)
			(stroke
				(width 0.1)
				(type default)
			)
			(layer "F.Fab")
		)
		(fp_line
			(start 0.67945 -0.3048)
			(end 0.67945 0.3048)
			(stroke
				(width 0.1)
				(type default)
			)
			(layer "F.Fab")
		)
		(fp_line
			(start -0.67945 -0.305054)
			(end -0.12065 -0.305054)
			(stroke
				(width 0.1)
				(type default)
			)
			(layer "F.Fab")
		)
		(fp_line
			(start -0.12065 -0.305054)
			(end -0.12065 -0.2794)
			(stroke
				(width 0.1)
				(type default)
			)
			(layer "F.Fab")
		)
		(pad "1" smd circle
			(at -0.40005 0 270)
			(size 0 0)
			(layers "F.Cu" "F.Mask" "F.Paste")
			(net "V_VGAVS_R")
		)
		(pad "2" smd circle
			(at 0.40005 0 270)
			(size 0 0)
			(layers "F.Cu" "F.Mask" "F.Paste")
			(net "V_VGAVS")
		)
	)
	(footprint ""
		(layer "F.Cu")
		(at 74.168 -74.295 -90)
		(property "Reference" "R615"
			(at 0 0 270)
			(layer "F.SilkS")
			(hide yes)
			(effects
				(font
					(size 1.27 1.27)
				)
			)
		)
		(property "Value" ""
			(at 0 0 270)
			(layer "F.Fab")
			(effects
				(font
					(size 1.27 1.27)
				)
			)
		)
		(duplicate_pad_numbers_are_jumpers no)
		(fp_line
			(start -0.7874 0.4064)
			(end -0.7874 -0.4064)
			(stroke
				(width 0.1524)
				(type default)
			)
			(layer "F.SilkS")
		)
		(fp_line
			(start 0.7874 0.4064)
			(end -0.7874 0.4064)
			(stroke
				(width 0.1524)
				(type default)
			)
			(layer "F.SilkS")
		)
		(fp_line
			(start -0.7874 -0.4064)
			(end 0.7874 -0.4064)
			(stroke
				(width 0.1524)
				(type default)
			)
			(layer "F.SilkS")
		)
		(fp_line
			(start 0.7874 -0.4064)
			(end 0.7874 0.4064)
			(stroke
				(width 0.1524)
				(type default)
			)
			(layer "F.SilkS")
		)
		(fp_line
			(start -0.67945 0.3048)
			(end -0.67945 -0.305054)
			(stroke
				(width 0.1)
				(type default)
			)
			(layer "F.Fab")
		)
		(fp_line
			(start -0.12065 0.3048)
			(end -0.67945 0.3048)
			(stroke
				(width 0.1)
				(type default)
			)
			(layer "F.Fab")
		)
		(fp_line
			(start 0.120396 0.3048)
			(end 0.120396 0.2794)
			(stroke
				(width 0.1)
				(type default)
			)
			(layer "F.Fab")
		)
		(fp_line
			(start 0.67945 0.3048)
			(end 0.120396 0.3048)
			(stroke
				(width 0.1)
				(type default)
			)
			(layer "F.Fab")
		)
		(fp_line
			(start -0.12065 0.2794)
			(end -0.12065 0.3048)
			(stroke
				(width 0.1)
				(type default)
			)
			(layer "F.Fab")
		)
		(fp_line
			(start 0.120396 0.2794)
			(end -0.12065 0.2794)
			(stroke
				(width 0.1)
				(type default)
			)
			(layer "F.Fab")
		)
		(fp_line
			(start -0.12065 -0.2794)
			(end 0.12065 -0.2794)
			(stroke
				(width 0.1)
				(type default)
			)
			(layer "F.Fab")
		)
		(fp_line
			(start 0.12065 -0.2794)
			(end 0.12065 -0.3048)
			(stroke
				(width 0.1)
				(type default)
			)
			(layer "F.Fab")
		)
		(fp_line
			(start 0.12065 -0.3048)
			(end 0.67945 -0.3048)
			(stroke
				(width 0.1)
				(type default)
			)
			(layer "F.Fab")
		)
		(fp_line
			(start 0.67945 -0.3048)
			(end 0.67945 0.3048)
			(stroke
				(width 0.1)
				(type default)
			)
			(layer "F.Fab")
		)
		(fp_line
			(start -0.67945 -0.305054)
			(end -0.12065 -0.305054)
			(stroke
				(width 0.1)
				(type default)
			)
			(layer "F.Fab")
		)
		(fp_line
			(start -0.12065 -0.305054)
			(end -0.12065 -0.2794)
			(stroke
				(width 0.1)
				(type default)
			)
			(layer "F.Fab")
		)
		(pad "1" smd circle
			(at -0.40005 0 270)
			(size 0 0)
			(layers "F.Cu" "F.Mask" "F.Paste")
			(net "P3V3_AUX")
		)
		(pad "2" smd circle
			(at 0.40005 0 270)
			(size 0 0)
			(layers "F.Cu" "F.Mask" "F.Paste")
			(net "FM_BMC_DISABLE")
		)
	)
	(footprint ""
		(layer "F.Cu")
		(at 44.4754 -107.9246 -90)
		(property "Reference" "R483"
			(at 0 0 270)
			(layer "F.SilkS")
			(hide yes)
			(effects
				(font
					(size 1.27 1.27)
				)
			)
		)
		(property "Value" ""
			(at 0 0 270)
			(layer "F.Fab")
			(effects
				(font
					(size 1.27 1.27)
				)
			)
		)
		(duplicate_pad_numbers_are_jumpers no)
		(fp_line
			(start -0.7874 0.4064)
			(end -0.7874 -0.4064)
			(stroke
				(width 0.1524)
				(type default)
			)
			(layer "F.SilkS")
		)
		(fp_line
			(start 0.7874 0.4064)
			(end -0.7874 0.4064)
			(stroke
				(width 0.1524)
				(type default)
			)
			(layer "F.SilkS")
		)
		(fp_line
			(start -0.7874 -0.4064)
			(end 0.7874 -0.4064)
			(stroke
				(width 0.1524)
				(type default)
			)
			(layer "F.SilkS")
		)
		(fp_line
			(start 0.7874 -0.4064)
			(end 0.7874 0.4064)
			(stroke
				(width 0.1524)
				(type default)
			)
			(layer "F.SilkS")
		)
		(fp_line
			(start -0.67945 0.3048)
			(end -0.67945 -0.305054)
			(stroke
				(width 0.1)
				(type default)
			)
			(layer "F.Fab")
		)
		(fp_line
			(start -0.12065 0.3048)
			(end -0.67945 0.3048)
			(stroke
				(width 0.1)
				(type default)
			)
			(layer "F.Fab")
		)
		(fp_line
			(start 0.120396 0.3048)
			(end 0.120396 0.2794)
			(stroke
				(width 0.1)
				(type default)
			)
			(layer "F.Fab")
		)
		(fp_line
			(start 0.67945 0.3048)
			(end 0.120396 0.3048)
			(stroke
				(width 0.1)
				(type default)
			)
			(layer "F.Fab")
		)
		(fp_line
			(start -0.12065 0.2794)
			(end -0.12065 0.3048)
			(stroke
				(width 0.1)
				(type default)
			)
			(layer "F.Fab")
		)
		(fp_line
			(start 0.120396 0.2794)
			(end -0.12065 0.2794)
			(stroke
				(width 0.1)
				(type default)
			)
			(layer "F.Fab")
		)
		(fp_line
			(start -0.12065 -0.2794)
			(end 0.12065 -0.2794)
			(stroke
				(width 0.1)
				(type default)
			)
			(layer "F.Fab")
		)
		(fp_line
			(start 0.12065 -0.2794)
			(end 0.12065 -0.3048)
			(stroke
				(width 0.1)
				(type default)
			)
			(layer "F.Fab")
		)
		(fp_line
			(start 0.12065 -0.3048)
			(end 0.67945 -0.3048)
			(stroke
				(width 0.1)
				(type default)
			)
			(layer "F.Fab")
		)
		(fp_line
			(start 0.67945 -0.3048)
			(end 0.67945 0.3048)
			(stroke
				(width 0.1)
				(type default)
			)
			(layer "F.Fab")
		)
		(fp_line
			(start -0.67945 -0.305054)
			(end -0.12065 -0.305054)
			(stroke
				(width 0.1)
				(type default)
			)
			(layer "F.Fab")
		)
		(fp_line
			(start -0.12065 -0.305054)
			(end -0.12065 -0.2794)
			(stroke
				(width 0.1)
				(type default)
			)
			(layer "F.Fab")
		)
		(pad "1" smd circle
			(at -0.40005 0 270)
			(size 0 0)
			(layers "F.Cu" "F.Mask" "F.Paste")
			(net "SPI_PCH_MUXED_IO2")
		)
		(pad "2" smd circle
			(at 0.40005 0 270)
			(size 0 0)
			(layers "F.Cu" "F.Mask" "F.Paste")
			(net "SPI_PCH_IO2_FLASH_R1")
		)
	)
)
